(kicad_pcb
	(version 20240108)
	(generator "pcbnew")
	(generator_version "8.0")
	(general
		(thickness 1.6)
		(legacy_teardrops no)
	)
	(paper "A4")
	(title_block
		(title "Jetson Orin Baseboard OCuLink Expansion")
		(date "2025-03-18")
		(rev "1.1.0")
		(company "Antmicro Ltd")
		(comment 1 "www.antmicro.com")
		(comment 9 "footprints 6-10 of 119")
	)
	(layers
		(0 "F.Cu" signal)
		(1 "In1.Cu" signal)
		(2 "In2.Cu" signal)
		(31 "B.Cu" signal)
		(32 "B.Adhes" user "B.Adhesive")
		(33 "F.Adhes" user "F.Adhesive")
		(34 "B.Paste" user)
		(35 "F.Paste" user)
		(36 "B.SilkS" user "B.Silkscreen")
		(37 "F.SilkS" user "F.Silkscreen")
		(38 "B.Mask" user)
		(39 "F.Mask" user)
		(40 "Dwgs.User" user "User.Drawings")
		(41 "Cmts.User" user "User.Comments")
		(42 "Eco1.User" user "User.Eco1")
		(43 "Eco2.User" user "User.Eco2")
		(44 "Edge.Cuts" user)
		(45 "Margin" user)
		(46 "B.CrtYd" user "B.Courtyard")
		(47 "F.CrtYd" user "F.Courtyard")
		(48 "B.Fab" user)
		(49 "F.Fab" user)
	)
	(footprint "antmicro-footprints:R_0402_1005Metric"
		(layer "F.Cu")
		(at 143.046 121.191 -90)
		(descr "Resistor SMD 0402")
		(tags "resistor SMD 0402")
		(property "Reference" "R47"
			(at -1.091 1.346 90)
			(layer "F.SilkS")
			(effects
				(font
					(size 0.7 0.7)
					(thickness 0.15)
				)
				(justify right top)
			)
		)
		(property "Value" "R_10k_0402"
			(at -1.011843 1.772047 90)
			(layer "F.Fab")
			(effects
				(font
					(size 0.7 0.7)
					(thickness 0.15)
				)
				(justify right top)
			)
		)
		(property "Footprint" "antmicro-footprints:R_0402_1005Metric"
			(at 0 0 90)
			(layer "F.Fab")
			(hide yes)
			(effects
				(font
					(size 1.27 1.27)
					(thickness 0.15)
				)
			)
		)
		(property "Datasheet" "https://www.bourns.com/docs/product-datasheets/cr.pdf"
			(at 0 0 90)
			(layer "F.Fab")
			(hide yes)
			(effects
				(font
					(size 1.27 1.27)
					(thickness 0.15)
				)
			)
		)
		(property "Description" "SMD Chip Resistor, 10 kohm, ± 1%, 62.5 mW, 0402 [1005 Metric], Thick Film, General Purpose"
			(at 0 0 90)
			(layer "F.Fab")
			(hide yes)
			(effects
				(font
					(size 1.27 1.27)
					(thickness 0.15)
				)
			)
		)
		(property "MPN" "CR0402-FX-1002GLF"
			(at 0 0 -90)
			(unlocked yes)
			(layer "F.Fab")
			(hide yes)
			(effects
				(font
					(size 1 1)
					(thickness 0.15)
				)
			)
		)
		(property "Manufacturer" "Bourns"
			(at 0 0 -90)
			(unlocked yes)
			(layer "F.Fab")
			(hide yes)
			(effects
				(font
					(size 1 1)
					(thickness 0.15)
				)
			)
		)
		(property "License" "Apache-2.0"
			(at 0 0 -90)
			(unlocked yes)
			(layer "F.Fab")
			(hide yes)
			(effects
				(font
					(size 1 1)
					(thickness 0.15)
				)
			)
		)
		(property "Author" "Antmicro"
			(at 0 0 -90)
			(unlocked yes)
			(layer "F.Fab")
			(hide yes)
			(effects
				(font
					(size 1 1)
					(thickness 0.15)
				)
			)
		)
		(property "Val" "10k"
			(at 0 0 -90)
			(unlocked yes)
			(layer "F.Fab")
			(hide yes)
			(effects
				(font
					(size 1 1)
					(thickness 0.15)
				)
			)
		)
		(property "Tolerance" "1%"
			(at 0 0 -90)
			(unlocked yes)
			(layer "F.Fab")
			(hide yes)
			(effects
				(font
					(size 1 1)
					(thickness 0.15)
				)
			)
		)
		(sheetname "Root")
		(sheetfile "jetson-orin-baseboard-oculink-expansion.kicad_sch")
		(attr smd)
		(fp_rect
			(start -0.925 -0.47)
			(end 0.925 0.47)
			(stroke
				(width 0.05)
				(type default)
			)
			(fill none)
			(layer "F.CrtYd")
		)
		(fp_rect
			(start -0.5 -0.25)
			(end 0.5 0.25)
			(stroke
				(width 0.15)
				(type solid)
			)
			(fill none)
			(layer "F.Fab")
		)
		(fp_text user "License: Apache-2.0"
			(at -0.95 5.169 90)
			(layer "F.Fab")
			(hide yes)
			(effects
				(font
					(size 0.7 0.7)
					(thickness 0.15)
				)
				(justify right top)
			)
		)
		(fp_text user "${REFERENCE}"
			(at -0.95 3.168 90)
			(layer "F.Fab")
			(hide yes)
			(effects
				(font
					(size 0.7 0.7)
					(thickness 0.15)
				)
				(justify right top)
			)
		)
		(fp_text user "Author: Antmicro"
			(at -0.95 4.169 90)
			(layer "F.Fab")
			(hide yes)
			(effects
				(font
					(size 0.7 0.7)
					(thickness 0.15)
				)
				(justify right top)
			)
		)
		(pad "1" smd roundrect
			(at -0.48 0 270)
			(size 0.59 0.64)
			(layers "F.Cu" "F.Paste" "F.Mask")
			(roundrect_rratio 0.25)
			(net 52 "+5V")
			(pintype "passive")
		)
		(pad "2" smd roundrect
			(at 0.48 0 270)
			(size 0.59 0.64)
			(layers "F.Cu" "F.Paste" "F.Mask")
			(roundrect_rratio 0.25)
			(net 138 "Net-(U5-FLG)")
			(pintype "passive")
		)
	)
	(footprint "antmicro-footprints:R_0402_1005Metric"
		(layer "F.Cu")
		(at 131.46 116.23 180)
		(descr "Resistor SMD 0402")
		(tags "resistor SMD 0402")
		(property "Reference" "R37"
			(at -2.26 1.29 180)
			(layer "F.SilkS")
			(effects
				(font
					(size 0.7 0.7)
					(thickness 0.15)
				)
				(justify right top)
			)
		)
		(property "Value" "R_0R_0402"
			(at -1.011843 1.772047 0)
			(layer "F.Fab")
			(effects
				(font
					(size 0.7 0.7)
					(thickness 0.15)
				)
				(justify right top)
			)
		)
		(property "Footprint" "antmicro-footprints:R_0402_1005Metric"
			(at 0 0 0)
			(layer "F.Fab")
			(hide yes)
			(effects
				(font
					(size 1.27 1.27)
					(thickness 0.15)
				)
			)
		)
		(property "Datasheet" "https://industrial.panasonic.com/cdbs/www-data/pdf/RDA0000/AOA0000C301.pdf"
			(at 0 0 0)
			(layer "F.Fab")
			(hide yes)
			(effects
				(font
					(size 1.27 1.27)
					(thickness 0.15)
				)
			)
		)
		(property "Description" "SMD Chip Resistor, Jumper, 0 ohm, 100 mW, 0402 [1005 Metric], Thick Film, General Purpose"
			(at 0 0 0)
			(layer "F.Fab")
			(hide yes)
			(effects
				(font
					(size 1.27 1.27)
					(thickness 0.15)
				)
			)
		)
		(property "MPN" "ERJ2GE0R00X"
			(at 0 0 180)
			(unlocked yes)
			(layer "F.Fab")
			(hide yes)
			(effects
				(font
					(size 1 1)
					(thickness 0.15)
				)
			)
		)
		(property "Manufacturer" "Panasonic"
			(at 0 0 180)
			(unlocked yes)
			(layer "F.Fab")
			(hide yes)
			(effects
				(font
					(size 1 1)
					(thickness 0.15)
				)
			)
		)
		(property "License" "Apache-2.0"
			(at 0 0 180)
			(unlocked yes)
			(layer "F.Fab")
			(hide yes)
			(effects
				(font
					(size 1 1)
					(thickness 0.15)
				)
			)
		)
		(property "Author" "Antmicro"
			(at 0 0 180)
			(unlocked yes)
			(layer "F.Fab")
			(hide yes)
			(effects
				(font
					(size 1 1)
					(thickness 0.15)
				)
			)
		)
		(property "Val" "0R"
			(at 0 0 180)
			(unlocked yes)
			(layer "F.Fab")
			(hide yes)
			(effects
				(font
					(size 1 1)
					(thickness 0.15)
				)
			)
		)
		(property "Tolerance" ""
			(at 0 0 180)
			(unlocked yes)
			(layer "F.Fab")
			(hide yes)
			(effects
				(font
					(size 1 1)
					(thickness 0.15)
				)
			)
		)
		(property "Current" "1A"
			(at 0 0 180)
			(unlocked yes)
			(layer "F.Fab")
			(hide yes)
			(effects
				(font
					(size 1 1)
					(thickness 0.15)
				)
			)
		)
		(property "Public" "False"
			(at 0 0 180)
			(unlocked yes)
			(layer "F.Fab")
			(hide yes)
			(effects
				(font
					(size 1 1)
					(thickness 0.15)
				)
			)
		)
		(sheetname "Root")
		(sheetfile "jetson-orin-baseboard-oculink-expansion.kicad_sch")
		(attr smd dnp)
		(fp_rect
			(start -0.925 -0.47)
			(end 0.925 0.47)
			(stroke
				(width 0.05)
				(type default)
			)
			(fill none)
			(layer "F.CrtYd")
		)
		(fp_rect
			(start -0.5 -0.25)
			(end 0.5 0.25)
			(stroke
				(width 0.15)
				(type solid)
			)
			(fill none)
			(layer "F.Fab")
		)
		(fp_text user "Author: Antmicro"
			(at -0.95 4.169 0)
			(layer "F.Fab")
			(hide yes)
			(effects
				(font
					(size 0.7 0.7)
					(thickness 0.15)
				)
				(justify right top)
			)
		)
		(fp_text user "${REFERENCE}"
			(at -0.95 3.168 0)
			(layer "F.Fab")
			(hide yes)
			(effects
				(font
					(size 0.7 0.7)
					(thickness 0.15)
				)
				(justify right top)
			)
		)
		(fp_text user "License: Apache-2.0"
			(at -0.95 5.169 0)
			(layer "F.Fab")
			(hide yes)
			(effects
				(font
					(size 0.7 0.7)
					(thickness 0.15)
				)
				(justify right top)
			)
		)
		(pad "1" smd roundrect
			(at -0.48 0 180)
			(size 0.59 0.64)
			(layers "F.Cu" "F.Paste" "F.Mask")
			(roundrect_rratio 0.25)
			(net 64 "/I2C_SCL")
			(pintype "passive")
		)
		(pad "2" smd roundrect
			(at 0.48 0 180)
			(size 0.59 0.64)
			(layers "F.Cu" "F.Paste" "F.Mask")
			(roundrect_rratio 0.25)
			(net 106 "Net-(U2-SCL)")
			(pintype "passive")
		)
	)
	(footprint "antmicro-footprints:C_0402_1005Metric"
		(layer "F.Cu")
		(at 129.2 106.877 180)
		(descr "Capacitor SMD 0402")
		(tags "capacitor SMD 0402")
		(property "Reference" "C37"
			(at 0.92 0.37 0)
			(layer "F.SilkS")
			(effects
				(font
					(size 0.7 0.7)
					(thickness 0.15)
				)
				(justify right top)
			)
		)
		(property "Value" "C_220n_0402"
			(at -1.022927 2.155213 0)
			(layer "F.Fab")
			(effects
				(font
					(size 0.7 0.7)
					(thickness 0.15)
				)
				(justify right top)
			)
		)
		(property "Footprint" "antmicro-footprints:C_0402_1005Metric"
			(at 0 0 0)
			(layer "F.Fab")
			(hide yes)
			(effects
				(font
					(size 1.27 1.27)
					(thickness 0.15)
				)
			)
		)
		(property "Datasheet" "https://www.yageo.com/en/Chart/Download/pdf/CC0402KRX5R6BB224"
			(at 0 0 0)
			(layer "F.Fab")
			(hide yes)
			(effects
				(font
					(size 1.27 1.27)
					(thickness 0.15)
				)
			)
		)
		(property "Description" "SMD Multilayer Ceramic Capacitor, 0.22 µF, 10 V, 0402 [1005 Metric], ± 10%, X5R, CC Series"
			(at 0 0 0)
			(layer "F.Fab")
			(hide yes)
			(effects
				(font
					(size 1.27 1.27)
					(thickness 0.15)
				)
			)
		)
		(property "MPN" "CC0402KRX5R6BB224"
			(at 0 0 180)
			(unlocked yes)
			(layer "F.Fab")
			(hide yes)
			(effects
				(font
					(size 1 1)
					(thickness 0.15)
				)
			)
		)
		(property "Manufacturer" "YAGEO"
			(at 0 0 180)
			(unlocked yes)
			(layer "F.Fab")
			(hide yes)
			(effects
				(font
					(size 1 1)
					(thickness 0.15)
				)
			)
		)
		(property "License" "Apache-2.0"
			(at 0 0 180)
			(unlocked yes)
			(layer "F.Fab")
			(hide yes)
			(effects
				(font
					(size 1 1)
					(thickness 0.15)
				)
			)
		)
		(property "Author" "Antmicro"
			(at 0 0 180)
			(unlocked yes)
			(layer "F.Fab")
			(hide yes)
			(effects
				(font
					(size 1 1)
					(thickness 0.15)
				)
			)
		)
		(property "Val" "220n"
			(at 0 0 180)
			(unlocked yes)
			(layer "F.Fab")
			(hide yes)
			(effects
				(font
					(size 1 1)
					(thickness 0.15)
				)
			)
		)
		(property "Voltage" ""
			(at 0 0 180)
			(unlocked yes)
			(layer "F.Fab")
			(hide yes)
			(effects
				(font
					(size 1 1)
					(thickness 0.15)
				)
			)
		)
		(property "Dielectric" ""
			(at 0 0 180)
			(unlocked yes)
			(layer "F.Fab")
			(hide yes)
			(effects
				(font
					(size 1 1)
					(thickness 0.15)
				)
			)
		)
		(property "Public" "False"
			(at 0 0 180)
			(unlocked yes)
			(layer "F.Fab")
			(hide yes)
			(effects
				(font
					(size 1 1)
					(thickness 0.15)
				)
			)
		)
		(sheetname "Root")
		(sheetfile "jetson-orin-baseboard-oculink-expansion.kicad_sch")
		(attr smd)
		(fp_rect
			(start -0.925 -0.47)
			(end 0.925 0.47)
			(stroke
				(width 0.05)
				(type default)
			)
			(fill none)
			(layer "F.CrtYd")
		)
		(fp_line
			(start 0.504 0.248)
			(end -0.494 0.248)
			(stroke
				(width 0.15)
				(type solid)
			)
			(layer "F.Fab")
		)
		(fp_line
			(start 0.504 -0.25)
			(end 0.504 0.248)
			(stroke
				(width 0.15)
				(type solid)
			)
			(layer "F.Fab")
		)
		(fp_line
			(start -0.494 0.248)
			(end -0.494 -0.25)
			(stroke
				(width 0.15)
				(type solid)
			)
			(layer "F.Fab")
		)
		(fp_line
			(start -0.494 -0.25)
			(end 0.504 -0.25)
			(stroke
				(width 0.15)
				(type solid)
			)
			(layer "F.Fab")
		)
		(fp_text user "${REFERENCE}"
			(at -0.939 4.599 0)
			(layer "F.Fab")
			(hide yes)
			(effects
				(font
					(size 0.7 0.7)
					(thickness 0.15)
				)
				(justify right top)
			)
		)
		(fp_text user "Author: Antmicro"
			(at -0.939 3.399 0)
			(layer "F.Fab")
			(hide yes)
			(effects
				(font
					(size 0.7 0.7)
					(thickness 0.15)
				)
				(justify right top)
			)
		)
		(fp_text user "License: Apache-2.0"
			(at -0.939 5.799 0)
			(layer "F.Fab")
			(hide yes)
			(effects
				(font
					(size 0.7 0.7)
					(thickness 0.15)
				)
				(justify right top)
			)
		)
		(pad "1" smd roundrect
			(at -0.48 0 180)
			(size 0.59 0.64)
			(layers "F.Cu" "F.Paste" "F.Mask")
			(roundrect_rratio 0.25)
			(net 79 "/PCIE_{I}_RX1+")
			(pintype "passive")
		)
		(pad "2" smd roundrect
			(at 0.48 0 180)
			(size 0.59 0.64)
			(layers "F.Cu" "F.Paste" "F.Mask")
			(roundrect_rratio 0.25)
			(net 80 "/PCIE_{I}_C.RX1+")
			(pintype "passive")
		)
	)
	(footprint "antmicro-footprints:R_0402_1005Metric"
		(layer "F.Cu")
		(at 144 127.151 90)
		(descr "Resistor SMD 0402")
		(tags "resistor SMD 0402")
		(property "Reference" "R48"
			(at -1.1 1.4 90)
			(layer "F.SilkS")
			(effects
				(font
					(size 0.7 0.7)
					(thickness 0.15)
				)
				(justify left bottom)
			)
		)
		(property "Value" "R_11k3_0402"
			(at -1.011843 1.772047 90)
			(layer "F.Fab")
			(effects
				(font
					(size 0.7 0.7)
					(thickness 0.15)
				)
				(justify left bottom)
			)
		)
		(property "Footprint" "antmicro-footprints:R_0402_1005Metric"
			(at 0 0 90)
			(layer "F.Fab")
			(hide yes)
			(effects
				(font
					(size 1.27 1.27)
					(thickness 0.15)
				)
			)
		)
		(property "Datasheet" "https://www.bourns.com/docs/product-datasheets/cr.pdf"
			(at 0 0 90)
			(layer "F.Fab")
			(hide yes)
			(effects
				(font
					(size 1.27 1.27)
					(thickness 0.15)
				)
			)
		)
		(property "Description" "SMD Chip Resistor, 11.3 kohm, ± 1%, 62.5 mW, 0402 [1005 Metric], Thick Film, General Purpose"
			(at 0 0 90)
			(layer "F.Fab")
			(hide yes)
			(effects
				(font
					(size 1.27 1.27)
					(thickness 0.15)
				)
			)
		)
		(property "MPN" "CR0402-FX-1132GLF"
			(at 0 0 90)
			(unlocked yes)
			(layer "F.Fab")
			(hide yes)
			(effects
				(font
					(size 1 1)
					(thickness 0.15)
				)
			)
		)
		(property "Manufacturer" "Bourns"
			(at 0 0 90)
			(unlocked yes)
			(layer "F.Fab")
			(hide yes)
			(effects
				(font
					(size 1 1)
					(thickness 0.15)
				)
			)
		)
		(property "License" "Apache-2.0"
			(at 0 0 90)
			(unlocked yes)
			(layer "F.Fab")
			(hide yes)
			(effects
				(font
					(size 1 1)
					(thickness 0.15)
				)
			)
		)
		(property "Author" "Antmicro"
			(at 0 0 90)
			(unlocked yes)
			(layer "F.Fab")
			(hide yes)
			(effects
				(font
					(size 1 1)
					(thickness 0.15)
				)
			)
		)
		(property "Val" "11k3"
			(at 0 0 90)
			(unlocked yes)
			(layer "F.Fab")
			(hide yes)
			(effects
				(font
					(size 1 1)
					(thickness 0.15)
				)
			)
		)
		(property "Tolerance" "1%"
			(at 0 0 90)
			(unlocked yes)
			(layer "F.Fab")
			(hide yes)
			(effects
				(font
					(size 1 1)
					(thickness 0.15)
				)
			)
		)
		(sheetname "Root")
		(sheetfile "jetson-orin-baseboard-oculink-expansion.kicad_sch")
		(attr smd)
		(fp_rect
			(start -0.925 -0.47)
			(end 0.925 0.47)
			(stroke
				(width 0.05)
				(type default)
			)
			(fill none)
			(layer "F.CrtYd")
		)
		(fp_rect
			(start -0.5 -0.25)
			(end 0.5 0.25)
			(stroke
				(width 0.15)
				(type solid)
			)
			(fill none)
			(layer "F.Fab")
		)
		(fp_text user "License: Apache-2.0"
			(at -0.95 5.169 90)
			(layer "F.Fab")
			(hide yes)
			(effects
				(font
					(size 0.7 0.7)
					(thickness 0.15)
				)
				(justify left bottom)
			)
		)
		(fp_text user "${REFERENCE}"
			(at -0.95 3.168 90)
			(layer "F.Fab")
			(hide yes)
			(effects
				(font
					(size 0.7 0.7)
					(thickness 0.15)
				)
				(justify left bottom)
			)
		)
		(fp_text user "Author: Antmicro"
			(at -0.95 4.169 90)
			(layer "F.Fab")
			(hide yes)
			(effects
				(font
					(size 0.7 0.7)
					(thickness 0.15)
				)
				(justify left bottom)
			)
		)
		(pad "1" smd roundrect
			(at -0.48 0 90)
			(size 0.59 0.64)
			(layers "F.Cu" "F.Paste" "F.Mask")
			(roundrect_rratio 0.25)
			(net 51 "GND")
			(pintype "passive")
		)
		(pad "2" smd roundrect
			(at 0.48 0 90)
			(size 0.59 0.64)
			(layers "F.Cu" "F.Paste" "F.Mask")
			(roundrect_rratio 0.25)
			(net 139 "Net-(U5-ISET)")
			(pintype "passive")
		)
	)
	(footprint "antmicro-footprints:C_0402_1005Metric"
		(layer "F.Cu")
		(at 146.708 142.516 90)
		(descr "Capacitor SMD 0402")
		(tags "capacitor SMD 0402")
		(property "Reference" "C5"
			(at 0.916 0.492 90)
			(layer "F.SilkS")
			(effects
				(font
					(size 0.7 0.7)
					(thickness 0.15)
				)
				(justify left bottom)
			)
		)
		(property "Value" "C_100n_0402"
			(at -1.022927 2.155213 90)
			(layer "F.Fab")
			(effects
				(font
					(size 0.7 0.7)
					(thickness 0.15)
				)
				(justify left bottom)
			)
		)
		(property "Footprint" "antmicro-footprints:C_0402_1005Metric"
			(at 0 0 90)
			(layer "F.Fab")
			(hide yes)
			(effects
				(font
					(size 1.27 1.27)
					(thickness 0.15)
				)
			)
		)
		(property "Datasheet" "https://www.murata.com/products/productdetail?partno=GRM155R61H104KE14%23"
			(at 0 0 90)
			(layer "F.Fab")
			(hide yes)
			(effects
				(font
					(size 1.27 1.27)
					(thickness 0.15)
				)
			)
		)
		(property "Description" "SMD Multilayer Ceramic Capacitor, 0.1 µF, 50 V, 0402 [1005 Metric], ± 10%, X5R, GRM Series"
			(at 0 0 90)
			(layer "F.Fab")
			(hide yes)
			(effects
				(font
					(size 1.27 1.27)
					(thickness 0.15)
				)
			)
		)
		(property "MPN" "GRM155R61H104KE14D"
			(at 0 0 90)
			(unlocked yes)
			(layer "F.Fab")
			(hide yes)
			(effects
				(font
					(size 1 1)
					(thickness 0.15)
				)
			)
		)
		(property "Manufacturer" "Murata"
			(at 0 0 90)
			(unlocked yes)
			(layer "F.Fab")
			(hide yes)
			(effects
				(font
					(size 1 1)
					(thickness 0.15)
				)
			)
		)
		(property "License" "Apache-2.0"
			(at 0 0 90)
			(unlocked yes)
			(layer "F.Fab")
			(hide yes)
			(effects
				(font
					(size 1 1)
					(thickness 0.15)
				)
			)
		)
		(property "Author" "Antmicro"
			(at 0 0 90)
			(unlocked yes)
			(layer "F.Fab")
			(hide yes)
			(effects
				(font
					(size 1 1)
					(thickness 0.15)
				)
			)
		)
		(property "Val" "100n"
			(at 0 0 90)
			(unlocked yes)
			(layer "F.Fab")
			(hide yes)
			(effects
				(font
					(size 1 1)
					(thickness 0.15)
				)
			)
		)
		(property "Voltage" "50V"
			(at 0 0 90)
			(unlocked yes)
			(layer "F.Fab")
			(hide yes)
			(effects
				(font
					(size 1 1)
					(thickness 0.15)
				)
			)
		)
		(property "Dielectric" "X5R"
			(at 0 0 90)
			(unlocked yes)
			(layer "F.Fab")
			(hide yes)
			(effects
				(font
					(size 1 1)
					(thickness 0.15)
				)
			)
		)
		(sheetname "Root")
		(sheetfile "jetson-orin-baseboard-oculink-expansion.kicad_sch")
		(attr smd)
		(fp_rect
			(start -0.925 -0.47)
			(end 0.925 0.47)
			(stroke
				(width 0.05)
				(type default)
			)
			(fill none)
			(layer "F.CrtYd")
		)
		(fp_line
			(start 0.504 -0.25)
			(end 0.504 0.248)
			(stroke
				(width 0.15)
				(type solid)
			)
			(layer "F.Fab")
		)
		(fp_line
			(start -0.494 -0.25)
			(end 0.504 -0.25)
			(stroke
				(width 0.15)
				(type solid)
			)
			(layer "F.Fab")
		)
		(fp_line
			(start 0.504 0.248)
			(end -0.494 0.248)
			(stroke
				(width 0.15)
				(type solid)
			)
			(layer "F.Fab")
		)
		(fp_line
			(start -0.494 0.248)
			(end -0.494 -0.25)
			(stroke
				(width 0.15)
				(type solid)
			)
			(layer "F.Fab")
		)
		(fp_text user "${REFERENCE}"
			(at -0.939 4.599 90)
			(layer "F.Fab")
			(hide yes)
			(effects
				(font
					(size 0.7 0.7)
					(thickness 0.15)
				)
				(justify left bottom)
			)
		)
		(fp_text user "Author: Antmicro"
			(at -0.939 3.399 90)
			(layer "F.Fab")
			(hide yes)
			(effects
				(font
					(size 0.7 0.7)
					(thickness 0.15)
				)
				(justify left bottom)
			)
		)
		(fp_text user "License: Apache-2.0"
			(at -0.939 5.799 90)
			(layer "F.Fab")
			(hide yes)
			(effects
				(font
					(size 0.7 0.7)
					(thickness 0.15)
				)
				(justify left bottom)
			)
		)
		(pad "1" smd roundrect
			(at -0.48 0 90)
			(size 0.59 0.64)
			(layers "F.Cu" "F.Paste" "F.Mask")
			(roundrect_rratio 0.25)
			(net 51 "GND")
			(pintype "passive")
		)
		(pad "2" smd roundrect
			(at 0.48 0 90)
			(size 0.59 0.64)
			(layers "F.Cu" "F.Paste" "F.Mask")
			(roundrect_rratio 0.25)
			(net 20 "+1V8")
			(pintype "passive")
		)
	)
)
